# BASEBOARD_FAB2 (Tioga Pass) — schematic netlist excerpt (pin names and nets, part order shuffled) for the footprints in the layout excerpt that follows; sources: Cadence DE-HDL packaged netlist, KiCad conversion of Wiwynn_Tioga_Pass_MB.brd

C6U16  CAP  10UF 4V 20% X6S  pkg 0603LF  page 221 : A = PVDDQ_ABC ; B = GND

T1D4  TEST-PAD-12P-1-GP-U  pkg DISCRET-GB1  page 257
  DP  = L3_85OHM_5INCH_DN
  DN  = L3_85OHM_5INCH_DP
  GND(0)  = GND
  GND(1)  = GND
  GND(2)  = GND
  GND(3)  = GND
  GND(4)  = GND
  GND(5)  = GND
  GND(6)  = GND
  GND(7)  = GND
  GND(8)  = GND
  GND(9)  = GND

(kicad_pcb
	(version 20260206)
	(generator "pcbnew")
	(generator_version "10.0")
	(general
		(thickness 1.6)
		(legacy_teardrops no)
	)
	(paper "A4")
	(title_block
		(title "Wiwynn_Tioga_Pass_MB.brd")
		(comment 1 "Tioga Pass / footprints 4117-4118 of 4770")
	)
	(layers
		(0 "F.Cu" signal "TOP")
		(4 "In1.Cu" signal "L2GND")
		(6 "In2.Cu" signal "L3")
		(8 "In3.Cu" signal "L4GND")
		(10 "In4.Cu" signal "L5")
		(12 "In5.Cu" signal "L6GND")
		(14 "In6.Cu" signal "L7VCC")
		(16 "In7.Cu" signal "L8VCC")
		(18 "In8.Cu" signal "L9GND")
		(20 "In9.Cu" signal "L10")
		(22 "In10.Cu" signal "L11GND")
		(24 "In11.Cu" signal "L12")
		(26 "In12.Cu" signal "L13GND")
		(2 "B.Cu" signal "BOTTOM")
		(9 "F.Adhes" user "F.Adhesive")
		(11 "B.Adhes" user "B.Adhesive")
		(13 "F.Paste" user "Package Geometry/Pastemask Top")
		(15 "B.Paste" user "Package Geometry/Pastemask Bottom")
		(5 "F.SilkS" user "Ref Des/Silkscreen Top")
		(7 "B.SilkS" user "Ref Des/Silkscreen Bottom")
		(1 "F.Mask" user "Board Geometry/Soldermask Top")
		(3 "B.Mask" user "Board Geometry/Soldermask Bottom")
		(17 "Dwgs.User" user "User.Drawings")
		(19 "Cmts.User" user "User.Comments")
		(21 "Eco1.User" user "User.Eco1")
		(23 "Eco2.User" user "User.Eco2")
		(25 "Edge.Cuts" user "Board Geometry/Outline")
		(27 "Margin" user)
		(31 "F.CrtYd" user "Package Geometry/Place Bound Top")
		(29 "B.CrtYd" user "Package Geometry/Place Bound Bottom")
		(35 "F.Fab" user "Ref Des/Assembly Top")
		(33 "B.Fab" user "Ref Des/Assembly Bottom")
	)
	(footprint ""
		(layer "B.Cu")
		(at 183.67629 0.139192 180)
		(property "Reference" "C6U16"
			(at 0 0 0)
			(layer "B.SilkS")
			(hide yes)
			(effects
				(font
					(size 1.27 1.27)
				)
				(justify mirror)
			)
		)
		(property "Value" ""
			(at 0 0 0)
			(layer "B.Fab")
			(effects
				(font
					(size 1.27 1.27)
				)
				(justify mirror)
			)
		)
		(duplicate_pad_numbers_are_jumpers no)
		(fp_rect
			(start 0.4953 -0.2032)
			(end -0.4953 1.6002)
			(stroke
				(width 0)
				(type default)
			)
			(fill no)
			(layer "B.CrtYd")
		)
		(fp_line
			(start 0.4953 1.6002)
			(end 0.4953 -0.2032)
			(stroke
				(width 0.1)
				(type default)
			)
			(layer "B.Fab")
		)
		(fp_line
			(start 0.4953 -0.2032)
			(end -0.4953 -0.2032)
			(stroke
				(width 0.1)
				(type default)
			)
			(layer "B.Fab")
		)
		(fp_line
			(start -0.4953 1.6002)
			(end 0.4953 1.6002)
			(stroke
				(width 0.1)
				(type default)
			)
			(layer "B.Fab")
		)
		(fp_line
			(start -0.4953 -0.2032)
			(end -0.4953 1.6002)
			(stroke
				(width 0.1)
				(type default)
			)
			(layer "B.Fab")
		)
		(pad "1" smd rect
			(at 0 0)
			(size 0.762 0.889)
			(layers "B.Cu" "B.Mask" "B.Paste")
			(net "PVDDQ_ABC")
		)
		(pad "2" smd rect
			(at 0 1.397)
			(size 0.762 0.889)
			(layers "B.Cu" "B.Mask" "B.Paste")
			(net "GND")
		)
		(zone
			(layer "B.Cu")
			(hatch none 0.5)
			(connect_pads
				(clearance 0)
			)
			(min_thickness 0.25)
			(keepout
				(tracks not_allowed)
				(vias allowed)
				(pads allowed)
				(copperpour not_allowed)
				(footprints allowed)
			)
			(placement
				(enabled no)
				(sheetname "")
			)
			(fill
				(thermal_gap 0.5)
				(thermal_bridge_width 0.5)
				(island_removal_mode 0)
			)
			(polygon
				(pts
					(xy 183.29529 -0.305308) (xy 184.05729 -0.305308) (xy 184.05729 -0.813308) (xy 183.29529 -0.813308)
				)
			)
		)
	)
	(footprint ""
		(layer "B.Cu")
		(at 101.448616 -164.9857 90)
		(property "Reference" "T1D4"
			(at 0 0 90)
			(layer "B.SilkS")
			(hide yes)
			(effects
				(font
					(size 1.27 1.27)
				)
				(justify mirror)
			)
		)
		(property "Value" "*"
			(at 3.4036 -4.46405 90)
			(unlocked yes)
			(layer "B.Fab")
			(hide yes)
			(effects
				(font
					(size 0.889 0.889)
					(thickness 0.1524)
				)
				(justify mirror)
			)
		)
		(property "Device Type" "TEST-PAD-12P-1-GP-U_DISCRET-GBA"
			(at 3.4036 -5.98805 90)
			(unlocked yes)
			(layer "B.Fab")
			(hide yes)
			(effects
				(font
					(size 0.889 0.889)
					(thickness 0.1524)
				)
				(justify mirror)
			)
		)
		(duplicate_pad_numbers_are_jumpers no)
		(fp_line
			(start 2.3876 -4.826)
			(end -2.3622 -4.826)
			(stroke
				(width 0.1524)
				(type default)
			)
			(layer "B.SilkS")
		)
		(fp_line
			(start -2.3622 -4.826)
			(end -2.3622 3.4798)
			(stroke
				(width 0.1524)
				(type default)
			)
			(layer "B.SilkS")
		)
		(fp_line
			(start 2.3876 3.4798)
			(end 2.3876 -4.826)
			(stroke
				(width 0.1524)
				(type default)
			)
			(layer "B.SilkS")
		)
		(fp_line
			(start -2.3622 3.4798)
			(end 2.3876 3.4798)
			(stroke
				(width 0.1524)
				(type default)
			)
			(layer "B.SilkS")
		)
		(fp_rect
			(start 2.6416 3.7338)
			(end -2.6162 -5.08)
			(stroke
				(width 0)
				(type default)
			)
			(fill no)
			(layer "B.CrtYd")
		)
		(fp_rect
			(start 2.6416 3.7338)
			(end -2.6162 -5.08)
			(stroke
				(width 0)
				(type default)
			)
			(fill no)
			(layer "B.Fab")
		)
		(pad "1" smd circle
			(at -0.496824 -1.301496 270)
			(size 0.6604 0.6604)
			(layers "B.Cu" "B.Mask" "B.Paste")
			(net "L3_85OHM_5INCH_DN")
		)
		(pad "2" smd circle
			(at 0.503936 -1.301496 270)
			(size 0.6604 0.6604)
			(layers "B.Cu" "B.Mask" "B.Paste")
			(net "L3_85OHM_5INCH_DP")
		)
		(pad "3" smd custom
			(at 0.00889 0.370078 270)
			(size 0.74295 0.74295)
			(layers "B.Cu" "B.Mask" "B.Paste")
			(net "GND")
			(options
				(clearance outline)
				(anchor circle)
			)
			(primitives
				(gr_poly
					(pts
						(xy -2.1209 -1.4859) (xy 2.1209 -1.4859) (xy 2.1209 1.4859) (xy 1.08585 1.4859) (xy 1.08585 0.4699)
						(xy -1.08585 0.4699) (xy -1.08585 1.4859) (xy -2.1209 1.4859)
					)
					(width 0)
					(fill yes)
				)
			)
		)
		(pad "4" thru_hole circle
			(at -1.266444 -3.851656 270)
			(size 1.4478 1.4478)
			(drill 1.0414)
			(layers "*.Cu" "*.Mask")
			(remove_unused_layers no)
			(net "GND")
			(clearance 0.1524)
			(thermal_gap 0.1524)
		)
		(pad "5" thru_hole circle
			(at 1.273556 -3.851656 270)
			(size 1.4478 1.4478)
			(drill 1.0414)
			(layers "*.Cu" "*.Mask")
			(remove_unused_layers no)
			(net "GND")
			(clearance 0.1524)
			(thermal_gap 0.1524)
		)
		(pad "6" thru_hole circle
			(at -1.266444 2.498344 270)
			(size 1.4478 1.4478)
			(drill 1.0414)
			(layers "*.Cu" "*.Mask")
			(remove_unused_layers no)
			(net "GND")
			(clearance 0.1524)
			(thermal_gap 0.1524)
		)
		(pad "7" thru_hole circle
			(at 1.273556 2.498344 270)
			(size 1.4478 1.4478)
			(drill 1.0414)
			(layers "*.Cu" "*.Mask")
			(remove_unused_layers no)
			(net "GND")
			(clearance 0.1524)
			(thermal_gap 0.1524)
		)
		(pad "8" thru_hole circle
			(at -1.27 -0.4572 270)
			(size 0.7112 0.7112)
			(drill 0.4064)
			(layers "*.Cu" "*.Mask")
			(remove_unused_layers no)
			(net "GND")
			(clearance 0.1016)
			(thermal_gap 0.1016)
		)
		(pad "9" thru_hole circle
			(at -1.27 0.762 270)
			(size 0.7112 0.7112)
			(drill 0.4064)
			(layers "*.Cu" "*.Mask")
			(remove_unused_layers no)
			(net "GND")
			(clearance 0.1016)
			(thermal_gap 0.1016)
		)
		(pad "10" thru_hole circle
			(at 0.0254 0.762 270)
			(size 0.7112 0.7112)
			(drill 0.4064)
			(layers "*.Cu" "*.Mask")
			(remove_unused_layers no)
			(net "GND")
			(clearance 0.1016)
			(thermal_gap 0.1016)
		)
		(pad "11" thru_hole circle
			(at 1.27 0.762 270)
			(size 0.7112 0.7112)
			(drill 0.4064)
			(layers "*.Cu" "*.Mask")
			(remove_unused_layers no)
			(net "GND")
			(clearance 0.1016)
			(thermal_gap 0.1016)
		)
		(pad "12" thru_hole circle
			(at 1.27 -0.4572 270)
			(size 0.7112 0.7112)
			(drill 0.4064)
			(layers "*.Cu" "*.Mask")
			(remove_unused_layers no)
			(net "GND")
			(clearance 0.1016)
			(thermal_gap 0.1016)
		)
	)
)
